# T6G (Grand Teton) — schematic netlist excerpt (pin names and nets, part order shuffled) for the footprints in the layout excerpt that follows; sources: Cadence DE-HDL packaged netlist, KiCad conversion of 04192023_DAF0TMB3IC0_F0TG_MB_C_brd_V02_OCP.brd

R898  Q_RES  0 5% EMPTY  pkg 0603LF  page 356 : A = P0V9_CPU1_RT_2D ; B = P0V9_CPU1_RT3_2A_2D
PC6570  Q_CAPP  470UF 2.5V 20% SPCAP  pkg SMLF  page 363 : A = P0V9_CPU0_RT_2D ; B = GND

(kicad_pcb
	(version 20260206)
	(generator "pcbnew")
	(generator_version "10.0")
	(general
		(thickness 1.6)
		(legacy_teardrops no)
	)
	(paper "A4")
	(title_block
		(title "04192023_DAF0TMB3IC0_F0TG_MB_C_brd_V02_OCP.brd")
		(comment 1 "Grand Teton / footprints 5221-5222 of 8354")
	)
	(layers
		(0 "F.Cu" signal "TOP")
		(4 "In1.Cu" signal "GND")
		(6 "In2.Cu" signal "IN1")
		(8 "In3.Cu" signal "GND1")
		(10 "In4.Cu" signal "IN2")
		(12 "In5.Cu" signal "GND2")
		(14 "In6.Cu" signal "IN3")
		(16 "In7.Cu" signal "GND3")
		(18 "In8.Cu" signal "VCC")
		(20 "In9.Cu" signal "VCC1")
		(22 "In10.Cu" signal "GND4")
		(24 "In11.Cu" signal "IN4")
		(26 "In12.Cu" signal "GND5")
		(28 "In13.Cu" signal "IN5")
		(30 "In14.Cu" signal "GND6")
		(32 "In15.Cu" signal "IN6")
		(34 "In16.Cu" signal "GND7")
		(2 "B.Cu" signal "BOTTOM")
		(9 "F.Adhes" user "F.Adhesive")
		(11 "B.Adhes" user "B.Adhesive")
		(13 "F.Paste" user "Package Geometry/Pastemask Top")
		(15 "B.Paste" user "Package Geometry/Pastemask Bottom")
		(5 "F.SilkS" user "Ref Des/Silkscreen Top")
		(7 "B.SilkS" user "Ref Des/Silkscreen Bottom")
		(1 "F.Mask" user "Board Geometry/Soldermask Top")
		(3 "B.Mask" user "Board Geometry/Soldermask Bottom")
		(17 "Dwgs.User" user "User.Drawings")
		(19 "Cmts.User" user "User.Comments")
		(21 "Eco1.User" user "User.Eco1")
		(23 "Eco2.User" user "User.Eco2")
		(25 "Edge.Cuts" user "Board Geometry/Outline")
		(27 "Margin" user)
		(31 "F.CrtYd" user "Package Geometry/Place Bound Top")
		(29 "B.CrtYd" user "Package Geometry/Place Bound Bottom")
		(35 "F.Fab" user "Ref Des/Assembly Top")
		(33 "B.Fab" user "Ref Des/Assembly Bottom")
	)
	(footprint ""
		(layer "B.Cu")
		(at 449.932552 -380.027434 90)
		(property "Reference" "PC6570"
			(at -6.293104 2.314448 0)
			(unlocked yes)
			(layer "B.SilkS")
			(effects
				(font
					(size 0.7874 0.5842)
					(thickness 0.1524)
				)
				(justify left mirror)
			)
		)
		(property "Value" ""
			(at 0 0 90)
			(layer "B.Fab")
			(effects
				(font
					(size 1.27 1.27)
				)
				(justify mirror)
			)
		)
		(duplicate_pad_numbers_are_jumpers no)
		(fp_line
			(start 4.84378 -2.150618)
			(end 4.53898 -2.150618)
			(stroke
				(width 0.1524)
				(type default)
			)
			(layer "B.SilkS")
		)
		(fp_line
			(start 4.84378 -2.150618)
			(end 4.842256 2.163064)
			(stroke
				(width 0.1524)
				(type default)
			)
			(layer "B.SilkS")
		)
		(fp_line
			(start 4.69138 -2.150618)
			(end 4.692396 2.161032)
			(stroke
				(width 0.1524)
				(type default)
			)
			(layer "B.SilkS")
		)
		(fp_line
			(start 4.53898 -2.150618)
			(end 4.539742 2.152142)
			(stroke
				(width 0.1524)
				(type default)
			)
			(layer "B.SilkS")
		)
		(fp_line
			(start 4.53898 -2.15011)
			(end -4.53898 -2.15011)
			(stroke
				(width 0.1524)
				(type default)
			)
			(layer "B.SilkS")
		)
		(fp_line
			(start -4.53898 -2.15011)
			(end -4.53898 2.15011)
			(stroke
				(width 0.1524)
				(type default)
			)
			(layer "B.SilkS")
		)
		(fp_line
			(start 4.53898 2.15011)
			(end 4.53898 -2.15011)
			(stroke
				(width 0.1524)
				(type default)
			)
			(layer "B.SilkS")
		)
		(fp_line
			(start -4.53898 2.15011)
			(end 4.53898 2.15011)
			(stroke
				(width 0.1524)
				(type default)
			)
			(layer "B.SilkS")
		)
		(fp_line
			(start 4.83108 2.150364)
			(end 4.447794 2.149348)
			(stroke
				(width 0.1524)
				(type default)
			)
			(layer "B.SilkS")
		)
		(fp_line
			(start 3.64998 -2.15011)
			(end -3.64998 -2.15011)
			(stroke
				(width 0.1)
				(type default)
			)
			(layer "B.Fab")
		)
		(fp_line
			(start -3.64998 -2.15011)
			(end -3.64998 2.15011)
			(stroke
				(width 0.1)
				(type default)
			)
			(layer "B.Fab")
		)
		(fp_line
			(start 3.64998 2.15011)
			(end 3.64998 -2.15011)
			(stroke
				(width 0.1)
				(type default)
			)
			(layer "B.Fab")
		)
		(fp_line
			(start -3.64998 2.15011)
			(end 3.64998 2.15011)
			(stroke
				(width 0.1)
				(type default)
			)
			(layer "B.Fab")
		)
		(fp_text user "-"
			(at -4.313174 -0.094488 90)
			(unlocked yes)
			(layer "B.SilkS")
			(effects
				(font
					(size 1.905 1.4224)
					(thickness 0.1524)
				)
				(justify left mirror)
			)
		)
		(fp_text user "+"
			(at 6.179566 0.060198 90)
			(unlocked yes)
			(layer "B.SilkS")
			(effects
				(font
					(size 1.905 1.4224)
					(thickness 0.1524)
				)
				(justify left mirror)
			)
		)
		(fp_text user "+"
			(at 6.214872 -0.337058 90)
			(unlocked yes)
			(layer "B.Fab")
			(effects
				(font
					(size 1.905 1.4224)
					(thickness 0.1524)
				)
				(justify left mirror)
			)
		)
		(fp_text user "-"
			(at -4.313174 -0.094488 90)
			(unlocked yes)
			(layer "B.Fab")
			(effects
				(font
					(size 1.905 1.4224)
					(thickness 0.1524)
				)
				(justify left mirror)
			)
		)
		(pad "1" smd rect
			(at 3.199892 0 270)
			(size 2.413 2.8194)
			(layers "B.Cu" "B.Mask" "B.Paste")
			(net "P0V9_CPU0_RT_2D")
		)
		(pad "2" smd rect
			(at -3.199892 0 270)
			(size 2.413 2.8194)
			(layers "B.Cu" "B.Mask" "B.Paste")
			(net "GND")
		)
	)
	(footprint ""
		(layer "B.Cu")
		(at 106.98861 -393.242546 180)
		(property "Reference" "R898"
			(at 0 0 0)
			(layer "B.SilkS")
			(hide yes)
			(effects
				(font
					(size 1.27 1.27)
				)
				(justify mirror)
			)
		)
		(property "Value" ""
			(at 0 0 0)
			(layer "B.Fab")
			(effects
				(font
					(size 1.27 1.27)
				)
				(justify mirror)
			)
		)
		(duplicate_pad_numbers_are_jumpers no)
		(fp_line
			(start 1.2954 0.5842)
			(end 1.2954 -0.5842)
			(stroke
				(width 0.1524)
				(type default)
			)
			(layer "B.SilkS")
		)
		(fp_line
			(start 1.2954 -0.5842)
			(end -1.2954 -0.5842)
			(stroke
				(width 0.1524)
				(type default)
			)
			(layer "B.SilkS")
		)
		(fp_line
			(start -1.2954 0.5842)
			(end 1.2954 0.5842)
			(stroke
				(width 0.1524)
				(type default)
			)
			(layer "B.SilkS")
		)
		(fp_line
			(start -1.2954 -0.5842)
			(end -1.2954 0.5842)
			(stroke
				(width 0.1524)
				(type default)
			)
			(layer "B.SilkS")
		)
		(fp_line
			(start 1.1938 0.4064)
			(end 1.1938 -0.406654)
			(stroke
				(width 0.1)
				(type default)
			)
			(layer "B.Fab")
		)
		(fp_line
			(start 1.1938 -0.406654)
			(end 0.8636 -0.406654)
			(stroke
				(width 0.1)
				(type default)
			)
			(layer "B.Fab")
		)
		(fp_line
			(start 0.8636 0.4572)
			(end 0.8636 0.4318)
			(stroke
				(width 0.1)
				(type default)
			)
			(layer "B.Fab")
		)
		(fp_line
			(start 0.8636 0.4318)
			(end 0.8636 0.4064)
			(stroke
				(width 0.1)
				(type default)
			)
			(layer "B.Fab")
		)
		(fp_line
			(start 0.8636 0.4064)
			(end 1.1938 0.4064)
			(stroke
				(width 0.1)
				(type default)
			)
			(layer "B.Fab")
		)
		(fp_line
			(start 0.8636 -0.406654)
			(end 0.8636 -0.4572)
			(stroke
				(width 0.1)
				(type default)
			)
			(layer "B.Fab")
		)
		(fp_line
			(start 0.8636 -0.4572)
			(end -0.8636 -0.4572)
			(stroke
				(width 0.1)
				(type default)
			)
			(layer "B.Fab")
		)
		(fp_line
			(start -0.8636 0.4572)
			(end 0.8636 0.4572)
			(stroke
				(width 0.1)
				(type default)
			)
			(layer "B.Fab")
		)
		(fp_line
			(start -0.8636 0.4064)
			(end -0.8636 0.4572)
			(stroke
				(width 0.1)
				(type default)
			)
			(layer "B.Fab")
		)
		(fp_line
			(start -0.8636 -0.406654)
			(end -1.1938 -0.406654)
			(stroke
				(width 0.1)
				(type default)
			)
			(layer "B.Fab")
		)
		(fp_line
			(start -0.8636 -0.4572)
			(end -0.8636 -0.406654)
			(stroke
				(width 0.1)
				(type default)
			)
			(layer "B.Fab")
		)
		(fp_line
			(start -1.1938 0.4064)
			(end -0.8636 0.4064)
			(stroke
				(width 0.1)
				(type default)
			)
			(layer "B.Fab")
		)
		(fp_line
			(start -1.1938 -0.406654)
			(end -1.1938 0.4064)
			(stroke
				(width 0.1)
				(type default)
			)
			(layer "B.Fab")
		)
		(pad "1" smd rect
			(at 0.7366 0 90)
			(size 0.7112 0.8128)
			(layers "B.Cu" "B.Mask" "B.Paste")
			(net "P0V9_CPU1_RT_2D")
		)
		(pad "2" smd rect
			(at -0.7366 0 90)
			(size 0.7112 0.8128)
			(layers "B.Cu" "B.Mask" "B.Paste")
			(net "P0V9_CPU1_RT3_2A_2D")
		)
	)
)
